# T6G (Grand Teton) — schematic netlist excerpt (pin names and nets, part order shuffled) for the footprints in the layout excerpt that follows; sources: Cadence DE-HDL packaged netlist, KiCad conversion of 04192023_DAF0TMB3IC0_F0TG_MB_C_brd_V02_OCP.brd

R638  Q_RES  1K 1% CHIP  pkg 0402LF  page 83 : A = CPLD_JTAG_EN ; B = P3V3_AUX
PC300  Q_CAP  0.22UF 16V 10% X7R  pkg 0402  page 212 : A = SW_PVDDCR_CPU0_P1_BOOT3_RC ; B = SW_PVDDCR_CPU0_P1_PH3
C772  Q_CAP_DIFFBUS  DIFF BUS_0.22UF 6.3V 20% X6S  pkg C0201  page 66 : \1\ = P5E_CPU1_P2_TX_C_DN<0> ; \2\ = P5E_CPU1_P2_TX_DN<0>

(kicad_pcb
	(version 20260206)
	(generator "pcbnew")
	(generator_version "10.0")
	(general
		(thickness 1.6)
		(legacy_teardrops no)
	)
	(paper "A4")
	(title_block
		(title "04192023_DAF0TMB3IC0_F0TG_MB_C_brd_V02_OCP.brd")
		(comment 1 "Grand Teton / footprints 3057-3059 of 8354")
	)
	(layers
		(0 "F.Cu" signal "TOP")
		(4 "In1.Cu" signal "GND")
		(6 "In2.Cu" signal "IN1")
		(8 "In3.Cu" signal "GND1")
		(10 "In4.Cu" signal "IN2")
		(12 "In5.Cu" signal "GND2")
		(14 "In6.Cu" signal "IN3")
		(16 "In7.Cu" signal "GND3")
		(18 "In8.Cu" signal "VCC")
		(20 "In9.Cu" signal "VCC1")
		(22 "In10.Cu" signal "GND4")
		(24 "In11.Cu" signal "IN4")
		(26 "In12.Cu" signal "GND5")
		(28 "In13.Cu" signal "IN5")
		(30 "In14.Cu" signal "GND6")
		(32 "In15.Cu" signal "IN6")
		(34 "In16.Cu" signal "GND7")
		(2 "B.Cu" signal "BOTTOM")
		(9 "F.Adhes" user "F.Adhesive")
		(11 "B.Adhes" user "B.Adhesive")
		(13 "F.Paste" user "Package Geometry/Pastemask Top")
		(15 "B.Paste" user "Package Geometry/Pastemask Bottom")
		(5 "F.SilkS" user "Ref Des/Silkscreen Top")
		(7 "B.SilkS" user "Ref Des/Silkscreen Bottom")
		(1 "F.Mask" user "Board Geometry/Soldermask Top")
		(3 "B.Mask" user "Board Geometry/Soldermask Bottom")
		(17 "Dwgs.User" user "User.Drawings")
		(19 "Cmts.User" user "User.Comments")
		(21 "Eco1.User" user "User.Eco1")
		(23 "Eco2.User" user "User.Eco2")
		(25 "Edge.Cuts" user "Board Geometry/Outline")
		(27 "Margin" user)
		(31 "F.CrtYd" user "Package Geometry/Place Bound Top")
		(29 "B.CrtYd" user "Package Geometry/Place Bound Bottom")
		(35 "F.Fab" user "Ref Des/Assembly Top")
		(33 "B.Fab" user "Ref Des/Assembly Bottom")
	)
	(footprint ""
		(layer "F.Cu")
		(at 142.595092 -381.48006 180)
		(property "Reference" "C772"
			(at 0 0 180)
			(layer "F.SilkS")
			(hide yes)
			(effects
				(font
					(size 1.27 1.27)
				)
			)
		)
		(property "Value" ""
			(at 0 0 180)
			(layer "F.Fab")
			(effects
				(font
					(size 1.27 1.27)
				)
			)
		)
		(duplicate_pad_numbers_are_jumpers no)
		(fp_line
			(start 0.299974 0.150114)
			(end -0.299974 0.150114)
			(stroke
				(width 0.1)
				(type default)
			)
			(layer "F.Fab")
		)
		(fp_line
			(start 0.299974 -0.150114)
			(end 0.299974 0.150114)
			(stroke
				(width 0.1)
				(type default)
			)
			(layer "F.Fab")
		)
		(fp_line
			(start -0.299974 0.150114)
			(end -0.299974 -0.150114)
			(stroke
				(width 0.1)
				(type default)
			)
			(layer "F.Fab")
		)
		(fp_line
			(start -0.299974 -0.150114)
			(end 0.299974 -0.150114)
			(stroke
				(width 0.1)
				(type default)
			)
			(layer "F.Fab")
		)
		(pad "1" smd rect
			(at -0.2667 0 180)
			(size 0.3048 0.381)
			(layers "F.Cu" "F.Mask" "F.Paste")
			(net "P5E_CPU1_P2_TX_C_DN<0>")
		)
		(pad "2" smd rect
			(at 0.2667 0 180)
			(size 0.3048 0.381)
			(layers "F.Cu" "F.Mask" "F.Paste")
			(net "P5E_CPU1_P2_TX_DN<0>")
		)
	)
	(footprint ""
		(layer "F.Cu")
		(at 97.288096 -178.0413 90)
		(property "Reference" "PC300"
			(at 0 0 90)
			(layer "F.SilkS")
			(hide yes)
			(effects
				(font
					(size 1.27 1.27)
				)
			)
		)
		(property "Value" ""
			(at 0 0 90)
			(layer "F.Fab")
			(effects
				(font
					(size 1.27 1.27)
				)
			)
		)
		(duplicate_pad_numbers_are_jumpers no)
		(fp_line
			(start 0.7874 -0.4064)
			(end 0.7874 0.4064)
			(stroke
				(width 0.1524)
				(type default)
			)
			(layer "F.SilkS")
		)
		(fp_line
			(start -0.7874 -0.4064)
			(end 0.7874 -0.4064)
			(stroke
				(width 0.1524)
				(type default)
			)
			(layer "F.SilkS")
		)
		(fp_line
			(start 0.7874 0.4064)
			(end -0.7874 0.4064)
			(stroke
				(width 0.1524)
				(type default)
			)
			(layer "F.SilkS")
		)
		(fp_line
			(start -0.7874 0.4064)
			(end -0.7874 -0.4064)
			(stroke
				(width 0.1524)
				(type default)
			)
			(layer "F.SilkS")
		)
		(fp_line
			(start -0.12065 -0.305054)
			(end -0.12065 -0.2794)
			(stroke
				(width 0.1)
				(type default)
			)
			(layer "F.Fab")
		)
		(fp_line
			(start -0.67945 -0.305054)
			(end -0.12065 -0.305054)
			(stroke
				(width 0.1)
				(type default)
			)
			(layer "F.Fab")
		)
		(fp_line
			(start 0.67945 -0.3048)
			(end 0.67945 0.3048)
			(stroke
				(width 0.1)
				(type default)
			)
			(layer "F.Fab")
		)
		(fp_line
			(start 0.12065 -0.3048)
			(end 0.67945 -0.3048)
			(stroke
				(width 0.1)
				(type default)
			)
			(layer "F.Fab")
		)
		(fp_line
			(start 0.12065 -0.2794)
			(end 0.12065 -0.3048)
			(stroke
				(width 0.1)
				(type default)
			)
			(layer "F.Fab")
		)
		(fp_line
			(start -0.12065 -0.2794)
			(end 0.12065 -0.2794)
			(stroke
				(width 0.1)
				(type default)
			)
			(layer "F.Fab")
		)
		(fp_line
			(start 0.120396 0.2794)
			(end -0.12065 0.2794)
			(stroke
				(width 0.1)
				(type default)
			)
			(layer "F.Fab")
		)
		(fp_line
			(start -0.12065 0.2794)
			(end -0.12065 0.3048)
			(stroke
				(width 0.1)
				(type default)
			)
			(layer "F.Fab")
		)
		(fp_line
			(start 0.67945 0.3048)
			(end 0.120396 0.3048)
			(stroke
				(width 0.1)
				(type default)
			)
			(layer "F.Fab")
		)
		(fp_line
			(start 0.120396 0.3048)
			(end 0.120396 0.2794)
			(stroke
				(width 0.1)
				(type default)
			)
			(layer "F.Fab")
		)
		(fp_line
			(start -0.12065 0.3048)
			(end -0.67945 0.3048)
			(stroke
				(width 0.1)
				(type default)
			)
			(layer "F.Fab")
		)
		(fp_line
			(start -0.67945 0.3048)
			(end -0.67945 -0.305054)
			(stroke
				(width 0.1)
				(type default)
			)
			(layer "F.Fab")
		)
		(pad "1" smd circle
			(at -0.40005 0 90)
			(size 0 0)
			(layers "F.Cu" "F.Mask" "F.Paste")
			(net "SW_PVDDCR_CPU0_P1_BOOT3_RC")
		)
		(pad "2" smd circle
			(at 0.40005 0 90)
			(size 0 0)
			(layers "F.Cu" "F.Mask" "F.Paste")
			(net "SW_PVDDCR_CPU0_P1_PH3")
		)
	)
	(footprint ""
		(layer "F.Cu")
		(at 167.132 -119.344948 180)
		(property "Reference" "R638"
			(at 0 0 180)
			(layer "F.SilkS")
			(hide yes)
			(effects
				(font
					(size 1.27 1.27)
				)
			)
		)
		(property "Value" ""
			(at 0 0 180)
			(layer "F.Fab")
			(effects
				(font
					(size 1.27 1.27)
				)
			)
		)
		(duplicate_pad_numbers_are_jumpers no)
		(fp_line
			(start 0.7874 0.4064)
			(end -0.7874 0.4064)
			(stroke
				(width 0.1524)
				(type default)
			)
			(layer "F.SilkS")
		)
		(fp_line
			(start 0.7874 -0.4064)
			(end 0.7874 0.4064)
			(stroke
				(width 0.1524)
				(type default)
			)
			(layer "F.SilkS")
		)
		(fp_line
			(start -0.7874 0.4064)
			(end -0.7874 -0.4064)
			(stroke
				(width 0.1524)
				(type default)
			)
			(layer "F.SilkS")
		)
		(fp_line
			(start -0.7874 -0.4064)
			(end 0.7874 -0.4064)
			(stroke
				(width 0.1524)
				(type default)
			)
			(layer "F.SilkS")
		)
		(fp_line
			(start 0.67945 0.3048)
			(end 0.120396 0.3048)
			(stroke
				(width 0.1)
				(type default)
			)
			(layer "F.Fab")
		)
		(fp_line
			(start 0.67945 -0.3048)
			(end 0.67945 0.3048)
			(stroke
				(width 0.1)
				(type default)
			)
			(layer "F.Fab")
		)
		(fp_line
			(start 0.12065 -0.2794)
			(end 0.12065 -0.3048)
			(stroke
				(width 0.1)
				(type default)
			)
			(layer "F.Fab")
		)
		(fp_line
			(start 0.12065 -0.3048)
			(end 0.67945 -0.3048)
			(stroke
				(width 0.1)
				(type default)
			)
			(layer "F.Fab")
		)
		(fp_line
			(start 0.120396 0.3048)
			(end 0.120396 0.2794)
			(stroke
				(width 0.1)
				(type default)
			)
			(layer "F.Fab")
		)
		(fp_line
			(start 0.120396 0.2794)
			(end -0.12065 0.2794)
			(stroke
				(width 0.1)
				(type default)
			)
			(layer "F.Fab")
		)
		(fp_line
			(start -0.12065 0.3048)
			(end -0.67945 0.3048)
			(stroke
				(width 0.1)
				(type default)
			)
			(layer "F.Fab")
		)
		(fp_line
			(start -0.12065 0.2794)
			(end -0.12065 0.3048)
			(stroke
				(width 0.1)
				(type default)
			)
			(layer "F.Fab")
		)
		(fp_line
			(start -0.12065 -0.2794)
			(end 0.12065 -0.2794)
			(stroke
				(width 0.1)
				(type default)
			)
			(layer "F.Fab")
		)
		(fp_line
			(start -0.12065 -0.305054)
			(end -0.12065 -0.2794)
			(stroke
				(width 0.1)
				(type default)
			)
			(layer "F.Fab")
		)
		(fp_line
			(start -0.67945 0.3048)
			(end -0.67945 -0.305054)
			(stroke
				(width 0.1)
				(type default)
			)
			(layer "F.Fab")
		)
		(fp_line
			(start -0.67945 -0.305054)
			(end -0.12065 -0.305054)
			(stroke
				(width 0.1)
				(type default)
			)
			(layer "F.Fab")
		)
		(pad "1" smd circle
			(at -0.40005 0 180)
			(size 0 0)
			(layers "F.Cu" "F.Mask" "F.Paste")
			(net "CPLD_JTAG_EN")
		)
		(pad "2" smd circle
			(at 0.40005 0 180)
			(size 0 0)
			(layers "F.Cu" "F.Mask" "F.Paste")
			(net "P3V3_AUX")
		)
	)
)
